(kicad_pcb
	(version 20241229)
	(generator "pcbnew")
	(generator_version "9.0")
	(general
		(thickness 1.552)
		(legacy_teardrops no)
	)
	(paper "A4")
	(title_block
		(date "2023-07-25")
		(rev "1.1.4")
		(comment 9 "footprints 149-153 of 379")
	)
	(layers
		(0 "F.Cu" signal)
		(4 "In1.Cu" signal)
		(6 "In2.Cu" signal)
		(8 "In3.Cu" signal)
		(10 "In4.Cu" signal)
		(12 "In5.Cu" signal)
		(14 "In6.Cu" signal)
		(2 "B.Cu" signal)
		(9 "F.Adhes" user "F.Adhesive")
		(11 "B.Adhes" user "B.Adhesive")
		(13 "F.Paste" user)
		(15 "B.Paste" user)
		(5 "F.SilkS" user "F.Silkscreen")
		(7 "B.SilkS" user "B.Silkscreen")
		(1 "F.Mask" user)
		(3 "B.Mask" user)
		(17 "Dwgs.User" user "User.Drawings")
		(19 "Cmts.User" user "User.Comments")
		(21 "Eco1.User" user "User.Eco1")
		(23 "Eco2.User" user "User.Eco2")
		(25 "Edge.Cuts" user)
		(27 "Margin" user)
		(31 "F.CrtYd" user "F.Courtyard")
		(29 "B.CrtYd" user "B.Courtyard")
		(35 "F.Fab" user)
		(33 "B.Fab" user)
	)
	(footprint "antmicro-footprints:R_1206_3216Metric"
		(layer "F.Cu")
		(at 156.29 110.5)
		(property "Reference" "R4"
			(at -0.86 -1.36 0)
			(layer "F.SilkS")
			(effects
				(font
					(size 0.65 0.65)
					(thickness 0.15)
				)
				(justify left bottom)
			)
		)
		(property "Value" "R_0R_1206"
			(at 0 2 0)
			(layer "F.Fab")
			(hide yes)
			(effects
				(font
					(size 0.7 0.7)
					(thickness 0.15)
				)
				(justify left bottom)
			)
		)
		(property "Datasheet" "https://www.farnell.com/datasheets/2860635.pdf"
			(at 0 0 0)
			(layer "F.Fab")
			(hide yes)
			(effects
				(font
					(size 1.27 1.27)
					(thickness 0.15)
				)
			)
		)
		(property "Description" "Zero Ohm Resistor, Jumper, 1206 [3216 Metric], Thick Film, 250 mW, 2 A, Surface Mount Device"
			(at 0 0 0)
			(layer "F.Fab")
			(hide yes)
			(effects
				(font
					(size 1.27 1.27)
					(thickness 0.15)
				)
			)
		)
		(property "Author" "Antmicro"
			(at 0 0 0)
			(layer "F.Fab")
			(hide yes)
			(effects
				(font
					(size 1 1)
					(thickness 0.15)
				)
			)
		)
		(property "Current" "2A"
			(at 0 0 0)
			(layer "F.Fab")
			(hide yes)
			(effects
				(font
					(size 1 1)
					(thickness 0.15)
				)
			)
		)
		(property "License" "Apache-2.0"
			(at 0 0 0)
			(layer "F.Fab")
			(hide yes)
			(effects
				(font
					(size 1 1)
					(thickness 0.15)
				)
			)
		)
		(property "MPN" "MCMR12X000_PTL"
			(at 0 0 0)
			(layer "F.Fab")
			(hide yes)
			(effects
				(font
					(size 1 1)
					(thickness 0.15)
				)
			)
		)
		(property "Manufacturer" "Multicomp Pro"
			(at 0 0 0)
			(layer "F.Fab")
			(hide yes)
			(effects
				(font
					(size 1 1)
					(thickness 0.15)
				)
			)
		)
		(property "Tolerance" "~"
			(at 0 0 0)
			(layer "F.Fab")
			(hide yes)
			(effects
				(font
					(size 1 1)
					(thickness 0.15)
				)
			)
		)
		(property "Val" "0R"
			(at 0 0 0)
			(layer "F.Fab")
			(hide yes)
			(effects
				(font
					(size 1 1)
					(thickness 0.15)
				)
			)
		)
		(sheetname "/Power Supply/")
		(sheetfile "supply.kicad_sch")
		(attr smd)
		(fp_line
			(start 0.8 -0.899)
			(end -0.8 -0.899)
			(stroke
				(width 0.15)
				(type solid)
			)
			(layer "F.SilkS")
		)
		(fp_line
			(start 0.8 0.901)
			(end -0.8 0.901)
			(stroke
				(width 0.15)
				(type solid)
			)
			(layer "F.SilkS")
		)
		(fp_rect
			(start -2.325 -1.15)
			(end 2.325 1.15)
			(stroke
				(width 0.05)
				(type default)
			)
			(fill no)
			(layer "F.CrtYd")
		)
		(fp_line
			(start -1.601 -0.802)
			(end -1.601 0.8)
			(stroke
				(width 0.15)
				(type solid)
			)
			(layer "F.Fab")
		)
		(fp_line
			(start -1.601 -0.802)
			(end 1.6 -0.802)
			(stroke
				(width 0.15)
				(type solid)
			)
			(layer "F.Fab")
		)
		(fp_line
			(start -1.601 0.8)
			(end 1.6 0.8)
			(stroke
				(width 0.15)
				(type solid)
			)
			(layer "F.Fab")
		)
		(fp_line
			(start 1.6 -0.802)
			(end 1.6 0.8)
			(stroke
				(width 0.15)
				(type solid)
			)
			(layer "F.Fab")
		)
		(fp_text user "${REFERENCE}"
			(at -2.401 3.5 0)
			(layer "F.Fab")
			(effects
				(font
					(size 0.7 0.7)
					(thickness 0.15)
				)
				(justify left bottom)
			)
		)
		(fp_text user "License: Apache-2.0"
			(at -2.401 6.3 0)
			(layer "F.Fab")
			(effects
				(font
					(size 0.7 0.7)
					(thickness 0.15)
				)
				(justify left bottom)
			)
		)
		(fp_text user "Author: Antmicro"
			(at -2.401 4.899 0)
			(layer "F.Fab")
			(effects
				(font
					(size 0.7 0.7)
					(thickness 0.15)
				)
				(justify left bottom)
			)
		)
		(pad "1" smd roundrect
			(at -1.5 0.001)
			(size 1.15 1.8)
			(layers "F.Cu" "F.Mask" "F.Paste")
			(roundrect_rratio 0.25)
			(net 19 "FFC2_5V")
			(pintype "passive")
		)
		(pad "2" smd roundrect
			(at 1.5 0.001)
			(size 1.15 1.8)
			(layers "F.Cu" "F.Mask" "F.Paste")
			(roundrect_rratio 0.25)
			(net 329 "/Power Supply/FFC2_5V_1")
			(pintype "passive")
		)
	)
	(footprint "antmicro-footprints:R_0603_1608Metric"
		(layer "F.Cu")
		(at 138.79 107.6 90)
		(descr "Resistor SMD 0603")
		(tags "resistor SMD 0603")
		(property "Reference" "R29"
			(at -0.54 -1.96 90)
			(layer "F.SilkS")
			(effects
				(font
					(size 0.65 0.65)
					(thickness 0.15)
				)
				(justify left bottom)
			)
		)
		(property "Value" "R_0R_0603"
			(at 0 1.6 90)
			(layer "F.Fab")
			(hide yes)
			(effects
				(font
					(size 0.7 0.7)
					(thickness 0.15)
				)
				(justify left bottom)
			)
		)
		(property "Datasheet" "https://www.bourns.com/docs/product-datasheets/cr.pdf?sfvrsn=574d41f6_14"
			(at 0 0 90)
			(layer "F.Fab")
			(hide yes)
			(effects
				(font
					(size 1.27 1.27)
					(thickness 0.15)
				)
			)
		)
		(property "Description" "Zero Ohm Resistor, Jumper, 0603 [1608 Metric], Thick Film, 100 mW, 1 A, Surface Mount Device, CR"
			(at 0 0 90)
			(layer "F.Fab")
			(hide yes)
			(effects
				(font
					(size 1.27 1.27)
					(thickness 0.15)
				)
			)
		)
		(property "Author" "Antmicro"
			(at 246.39 -31.19 0)
			(layer "F.Fab")
			(hide yes)
			(effects
				(font
					(size 1 1)
					(thickness 0.15)
				)
			)
		)
		(property "Current" "1A"
			(at 246.39 -31.19 0)
			(layer "F.Fab")
			(hide yes)
			(effects
				(font
					(size 1 1)
					(thickness 0.15)
				)
			)
		)
		(property "License" "Apache-2.0"
			(at 246.39 -31.19 0)
			(layer "F.Fab")
			(hide yes)
			(effects
				(font
					(size 1 1)
					(thickness 0.15)
				)
			)
		)
		(property "MPN" "CR0603-J/-000ELF"
			(at 246.39 -31.19 0)
			(layer "F.Fab")
			(hide yes)
			(effects
				(font
					(size 1 1)
					(thickness 0.15)
				)
			)
		)
		(property "Manufacturer" "Bourns"
			(at 246.39 -31.19 0)
			(layer "F.Fab")
			(hide yes)
			(effects
				(font
					(size 1 1)
					(thickness 0.15)
				)
			)
		)
		(property "Tolerance" "~"
			(at 246.39 -31.19 0)
			(layer "F.Fab")
			(hide yes)
			(effects
				(font
					(size 1 1)
					(thickness 0.15)
				)
			)
		)
		(property "Val" "0R"
			(at 246.39 -31.19 0)
			(layer "F.Fab")
			(hide yes)
			(effects
				(font
					(size 1 1)
					(thickness 0.15)
				)
			)
		)
		(sheetname "/Power Supply/")
		(sheetfile "supply.kicad_sch")
		(attr smd)
		(fp_line
			(start -0.15 -0.4)
			(end 0.15 -0.4)
			(stroke
				(width 0.15)
				(type solid)
			)
			(layer "F.SilkS")
		)
		(fp_line
			(start -0.15 0.4)
			(end 0.15 0.4)
			(stroke
				(width 0.15)
				(type solid)
			)
			(layer "F.SilkS")
		)
		(fp_rect
			(start -1.25 -0.65)
			(end 1.25 0.65)
			(stroke
				(width 0.05)
				(type solid)
			)
			(fill no)
			(layer "F.CrtYd")
		)
		(fp_rect
			(start -0.8 -0.4)
			(end 0.8 0.4)
			(stroke
				(width 0.15)
				(type solid)
			)
			(fill no)
			(layer "F.Fab")
		)
		(fp_text user "Author: Antmicro"
			(at -1.25 4.9 90)
			(layer "F.Fab")
			(effects
				(font
					(size 0.7 0.7)
					(thickness 0.15)
				)
				(justify left bottom)
			)
		)
		(fp_text user "${REFERENCE}"
			(at -1.25 3.898 90)
			(layer "F.Fab")
			(effects
				(font
					(size 0.7 0.7)
					(thickness 0.15)
				)
				(justify left bottom)
			)
		)
		(fp_text user "License: Apache-2.0"
			(at -1.25 5.9 90)
			(layer "F.Fab")
			(effects
				(font
					(size 0.7 0.7)
					(thickness 0.15)
				)
				(justify left bottom)
			)
		)
		(pad "1" smd roundrect
			(at -0.7 0 90)
			(size 0.8 1)
			(layers "F.Cu" "F.Mask" "F.Paste")
			(roundrect_rratio 0.2)
			(net 272 "Net-(U8-V_{OUT})")
			(pintype "passive")
		)
		(pad "2" smd roundrect
			(at 0.7 0 90)
			(size 0.8 1)
			(layers "F.Cu" "F.Mask" "F.Paste")
			(roundrect_rratio 0.2)
			(net 49 "1V0_Clean")
			(pintype "passive")
		)
	)
	(footprint "antmicro-footprints:F_0603_1608Metric"
		(layer "F.Cu")
		(at 154.25 116.25 180)
		(property "Reference" "F1"
			(at 0.42 0.91 180)
			(layer "F.SilkS")
			(effects
				(font
					(size 0.65 0.65)
					(thickness 0.15)
				)
				(justify left bottom)
			)
		)
		(property "Value" "F_1.25A_0603"
			(at 0 1.7 180)
			(layer "F.Fab")
			(hide yes)
			(effects
				(font
					(size 0.7 0.7)
					(thickness 0.15)
				)
				(justify left bottom)
			)
		)
		(property "Datasheet" "https://www.littelfuse.com/~/media/electronics/datasheets/fuses/littelfuse_fuse_467_datasheet.pdf.pdf"
			(at 0 0 180)
			(layer "F.Fab")
			(hide yes)
			(effects
				(font
					(size 1.27 1.27)
					(thickness 0.15)
				)
			)
		)
		(property "Description" "Fuse, Surface Mount, 1.25 A, Very Fast Acting, 32 V, 32 V, 0603 (1608 Metric), 467"
			(at 0 0 180)
			(layer "F.Fab")
			(hide yes)
			(effects
				(font
					(size 1.27 1.27)
					(thickness 0.15)
				)
			)
		)
		(property "Author" "Antmicro"
			(at 308.5 232.5 0)
			(layer "F.Fab")
			(hide yes)
			(effects
				(font
					(size 1 1)
					(thickness 0.15)
				)
			)
		)
		(property "License" "Apache-2.0"
			(at 308.5 232.5 0)
			(layer "F.Fab")
			(hide yes)
			(effects
				(font
					(size 1 1)
					(thickness 0.15)
				)
			)
		)
		(property "MPN" "04671.25NR"
			(at 308.5 232.5 0)
			(layer "F.Fab")
			(hide yes)
			(effects
				(font
					(size 1 1)
					(thickness 0.15)
				)
			)
		)
		(property "Manufacturer" "Littelfuse"
			(at 308.5 232.5 0)
			(layer "F.Fab")
			(hide yes)
			(effects
				(font
					(size 1 1)
					(thickness 0.15)
				)
			)
		)
		(sheetname "/Peripherals/")
		(sheetfile "peripherals.kicad_sch")
		(attr smd)
		(fp_line
			(start -0.15 0.4)
			(end 0.15 0.4)
			(stroke
				(width 0.15)
				(type solid)
			)
			(layer "F.SilkS")
		)
		(fp_line
			(start -0.15 -0.4)
			(end 0.15 -0.4)
			(stroke
				(width 0.15)
				(type solid)
			)
			(layer "F.SilkS")
		)
		(fp_rect
			(start -1.25 -0.65)
			(end 1.25 0.65)
			(stroke
				(width 0.05)
				(type solid)
			)
			(fill no)
			(layer "F.CrtYd")
		)
		(fp_line
			(start 0.8 0.406)
			(end -0.803 0.406)
			(stroke
				(width 0.15)
				(type solid)
			)
			(layer "F.Fab")
		)
		(fp_line
			(start 0.8 -0.408)
			(end 0.8 0.406)
			(stroke
				(width 0.15)
				(type solid)
			)
			(layer "F.Fab")
		)
		(fp_line
			(start 0.8 -0.408)
			(end -0.803 -0.408)
			(stroke
				(width 0.15)
				(type solid)
			)
			(layer "F.Fab")
		)
		(fp_line
			(start -0.803 0.406)
			(end -0.803 -0.408)
			(stroke
				(width 0.15)
				(type solid)
			)
			(layer "F.Fab")
		)
		(fp_text user "Author: Antmicro"
			(at -1.653 3.162 180)
			(layer "F.Fab")
			(effects
				(font
					(size 0.7 0.7)
					(thickness 0.15)
				)
				(justify left bottom)
			)
		)
		(fp_text user "License: Apache-2.0"
			(at -1.653 5.9 180)
			(layer "F.Fab")
			(effects
				(font
					(size 0.7 0.7)
					(thickness 0.15)
				)
				(justify left bottom)
			)
		)
		(fp_text user "${REFERENCE}"
			(at -1.653 4.6 180)
			(layer "F.Fab")
			(effects
				(font
					(size 0.7 0.7)
					(thickness 0.15)
				)
				(justify left bottom)
			)
		)
		(pad "1" smd roundrect
			(at -0.7 0 180)
			(size 0.8 1)
			(layers "F.Cu" "F.Mask" "F.Paste")
			(roundrect_rratio 0.2)
			(net 2 "+3V3")
			(pintype "passive")
		)
		(pad "2" smd roundrect
			(at 0.7 0 180)
			(size 0.8 1)
			(layers "F.Cu" "F.Mask" "F.Paste")
			(roundrect_rratio 0.2)
			(net 331 "/Peripherals/3V3_MISC")
			(pintype "passive")
		)
	)
	(footprint "antmicro-footprints:R_0402_1005Metric"
		(layer "F.Cu")
		(at 167.2 96.6)
		(descr "Resistor SMD 0402")
		(tags "resistor SMD 0402")
		(property "Reference" "R73"
			(at -3.67 0.34 0)
			(layer "F.SilkS")
			(effects
				(font
					(size 0.65 0.65)
					(thickness 0.15)
				)
				(justify left bottom)
			)
		)
		(property "Value" "R_0R_0402"
			(at 0 1.4 0)
			(layer "F.Fab")
			(hide yes)
			(effects
				(font
					(size 0.7 0.7)
					(thickness 0.15)
				)
				(justify left bottom)
			)
		)
		(property "Datasheet" "https://industrial.panasonic.com/cdbs/www-data/pdf/RDA0000/AOA0000C301.pdf"
			(at 0 0 0)
			(layer "F.Fab")
			(hide yes)
			(effects
				(font
					(size 1.27 1.27)
					(thickness 0.15)
				)
			)
		)
		(property "Description" "SMD Chip Resistor, Jumper, 0 ohm, 100 mW, 0402 [1005 Metric], Thick Film, General Purpose"
			(at 0 0 0)
			(layer "F.Fab")
			(hide yes)
			(effects
				(font
					(size 1.27 1.27)
					(thickness 0.15)
				)
			)
		)
		(property "Author" "Antmicro"
			(at 0 0 0)
			(layer "F.Fab")
			(hide yes)
			(effects
				(font
					(size 1 1)
					(thickness 0.15)
				)
			)
		)
		(property "Current" "1A"
			(at 0 0 0)
			(layer "F.Fab")
			(hide yes)
			(effects
				(font
					(size 1 1)
					(thickness 0.15)
				)
			)
		)
		(property "License" "Apache-2.0"
			(at 0 0 0)
			(layer "F.Fab")
			(hide yes)
			(effects
				(font
					(size 1 1)
					(thickness 0.15)
				)
			)
		)
		(property "MPN" "ERJ2GE0R00X"
			(at 0 0 0)
			(layer "F.Fab")
			(hide yes)
			(effects
				(font
					(size 1 1)
					(thickness 0.15)
				)
			)
		)
		(property "Manufacturer" "Panasonic"
			(at 0 0 0)
			(layer "F.Fab")
			(hide yes)
			(effects
				(font
					(size 1 1)
					(thickness 0.15)
				)
			)
		)
		(property "Tolerance" "~"
			(at 0 0 0)
			(layer "F.Fab")
			(hide yes)
			(effects
				(font
					(size 1 1)
					(thickness 0.15)
				)
			)
		)
		(property "Val" "0R"
			(at 0 0 0)
			(layer "F.Fab")
			(hide yes)
			(effects
				(font
					(size 1 1)
					(thickness 0.15)
				)
			)
		)
		(sheetname "/Peripherals/")
		(sheetfile "peripherals.kicad_sch")
		(attr smd)
		(fp_rect
			(start -0.925 -0.47)
			(end 0.925 0.47)
			(stroke
				(width 0.05)
				(type default)
			)
			(fill no)
			(layer "F.CrtYd")
		)
		(fp_rect
			(start -0.5 -0.25)
			(end 0.5 0.25)
			(stroke
				(width 0.15)
				(type solid)
			)
			(fill no)
			(layer "F.Fab")
		)
		(fp_text user "${REFERENCE}"
			(at -0.95 3.168 0)
			(layer "F.Fab")
			(effects
				(font
					(size 0.7 0.7)
					(thickness 0.15)
				)
				(justify left bottom)
			)
		)
		(fp_text user "Author: Antmicro"
			(at -0.95 4.169 0)
			(layer "F.Fab")
			(effects
				(font
					(size 0.7 0.7)
					(thickness 0.15)
				)
				(justify left bottom)
			)
		)
		(fp_text user "License: Apache-2.0"
			(at -0.95 5.169 0)
			(layer "F.Fab")
			(effects
				(font
					(size 0.7 0.7)
					(thickness 0.15)
				)
				(justify left bottom)
			)
		)
		(pad "1" smd roundrect
			(at -0.48 0)
			(size 0.59 0.64)
			(layers "F.Cu" "F.Mask" "F.Paste")
			(roundrect_rratio 0.25)
			(net 88 "/Peripherals/FFC1_VSYNC0")
			(pintype "passive")
		)
		(pad "2" smd roundrect
			(at 0.48 0)
			(size 0.59 0.64)
			(layers "F.Cu" "F.Mask" "F.Paste")
			(roundrect_rratio 0.25)
			(net 56 "Net-(J4-Pad32)")
			(pintype "passive")
		)
	)
	(footprint "antmicro-footprints:TP_SMD_0.75mm"
		(layer "F.Cu")
		(at 104.3 98.7 -90)
		(property "Reference" "TP20"
			(at 0.42 0.46 180)
			(layer "F.SilkS")
			(effects
				(font
					(size 0.65 0.65)
					(thickness 0.15)
				)
				(justify right bottom)
			)
		)
		(property "Value" "TP_0.75mm_SMD"
			(at 0 1.2 90)
			(layer "F.Fab")
			(hide yes)
			(effects
				(font
					(size 0.7 0.7)
					(thickness 0.15)
				)
				(justify right bottom)
			)
		)
		(property "Description" "SMT test point"
			(at 0 0 270)
			(layer "F.Fab")
			(hide yes)
			(effects
				(font
					(size 1.27 1.27)
					(thickness 0.15)
				)
			)
		)
		(property "Author" "Antmicro"
			(at 5.6 203 0)
			(layer "F.Fab")
			(hide yes)
			(effects
				(font
					(size 1 1)
					(thickness 0.15)
				)
			)
		)
		(property "License" "Apache-2.0"
			(at 5.6 203 0)
			(layer "F.Fab")
			(hide yes)
			(effects
				(font
					(size 1 1)
					(thickness 0.15)
				)
			)
		)
		(property "MPN" ""
			(at 5.6 203 0)
			(layer "F.Fab")
			(hide yes)
			(effects
				(font
					(size 1 1)
					(thickness 0.15)
				)
			)
		)
		(property "Manufacturer" ""
			(at 5.6 203 0)
			(layer "F.Fab")
			(hide yes)
			(effects
				(font
					(size 1 1)
					(thickness 0.15)
				)
			)
		)
		(sheetname "/FPGA/")
		(sheetfile "fpga.kicad_sch")
		(attr exclude_from_pos_files)
		(fp_circle
			(center 0 0)
			(end 0.475 0)
			(stroke
				(width 0.05)
				(type default)
			)
			(fill no)
			(layer "F.CrtYd")
		)
		(fp_text user "${REFERENCE}"
			(at -0.4 2.7 270)
			(layer "F.Fab")
			(effects
				(font
					(size 0.7 0.7)
					(thickness 0.15)
				)
				(justify left bottom)
			)
		)
		(fp_text user "Author: Antmicro"
			(at -0.4 3.901 270)
			(layer "F.Fab")
			(effects
				(font
					(size 0.7 0.7)
					(thickness 0.15)
				)
				(justify left bottom)
			)
		)
		(fp_text user "License: Apache-2.0"
			(at -0.4 5.101 270)
			(layer "F.Fab")
			(effects
				(font
					(size 0.7 0.7)
					(thickness 0.15)
				)
				(justify left bottom)
			)
		)
		(pad "1" smd circle
			(at 0 0 270)
			(size 0.75 0.75)
			(layers "F.Cu" "F.Mask")
			(net 303 "Net-(U18-SCLK)")
			(pinfunction "1")
			(pintype "passive")
		)
	)
)
